# T6G (Grand Teton) — schematic netlist excerpt (pin names and nets, part order shuffled) for the footprints in the layout excerpt that follows; sources: Cadence DE-HDL packaged netlist, KiCad conversion of 04192023_DAF0TMB3IC0_F0TG_MB_C_brd_V02_OCP.brd

R633  Q_RES  2.2K 5% CHIP  pkg 0402LF  page 151 : A = PVDD18_S5_P0 ; B = SMB_CPU_5_SDA
R2656  Q_RES  100 1% EMPTY  pkg 0402LF  page 123 : A = HGX_DETECT_N_ISO ; B = GND
PC458_2  Q_CAP  22UF 4V 20% X6S  pkg C0805  page 222 : A = PVDDIO_P1 ; B = GND

(kicad_pcb
	(version 20260206)
	(generator "pcbnew")
	(generator_version "10.0")
	(general
		(thickness 1.6)
		(legacy_teardrops no)
	)
	(paper "A4")
	(title_block
		(title "04192023_DAF0TMB3IC0_F0TG_MB_C_brd_V02_OCP.brd")
		(comment 1 "Grand Teton / footprints 5546-5548 of 8354")
	)
	(layers
		(0 "F.Cu" signal "TOP")
		(4 "In1.Cu" signal "GND")
		(6 "In2.Cu" signal "IN1")
		(8 "In3.Cu" signal "GND1")
		(10 "In4.Cu" signal "IN2")
		(12 "In5.Cu" signal "GND2")
		(14 "In6.Cu" signal "IN3")
		(16 "In7.Cu" signal "GND3")
		(18 "In8.Cu" signal "VCC")
		(20 "In9.Cu" signal "VCC1")
		(22 "In10.Cu" signal "GND4")
		(24 "In11.Cu" signal "IN4")
		(26 "In12.Cu" signal "GND5")
		(28 "In13.Cu" signal "IN5")
		(30 "In14.Cu" signal "GND6")
		(32 "In15.Cu" signal "IN6")
		(34 "In16.Cu" signal "GND7")
		(2 "B.Cu" signal "BOTTOM")
		(9 "F.Adhes" user "F.Adhesive")
		(11 "B.Adhes" user "B.Adhesive")
		(13 "F.Paste" user "Package Geometry/Pastemask Top")
		(15 "B.Paste" user "Package Geometry/Pastemask Bottom")
		(5 "F.SilkS" user "Ref Des/Silkscreen Top")
		(7 "B.SilkS" user "Ref Des/Silkscreen Bottom")
		(1 "F.Mask" user "Board Geometry/Soldermask Top")
		(3 "B.Mask" user "Board Geometry/Soldermask Bottom")
		(17 "Dwgs.User" user "User.Drawings")
		(19 "Cmts.User" user "User.Comments")
		(21 "Eco1.User" user "User.Eco1")
		(23 "Eco2.User" user "User.Eco2")
		(25 "Edge.Cuts" user "Board Geometry/Outline")
		(27 "Margin" user)
		(31 "F.CrtYd" user "Package Geometry/Place Bound Top")
		(29 "B.CrtYd" user "Package Geometry/Place Bound Bottom")
		(35 "F.Fab" user "Ref Des/Assembly Top")
		(33 "B.Fab" user "Ref Des/Assembly Bottom")
	)
	(footprint ""
		(layer "B.Cu")
		(at 105.695242 -412.03372 90)
		(property "Reference" "R2656"
			(at 0 0 90)
			(layer "B.SilkS")
			(hide yes)
			(effects
				(font
					(size 1.27 1.27)
				)
				(justify mirror)
			)
		)
		(property "Value" ""
			(at 0 0 90)
			(layer "B.Fab")
			(effects
				(font
					(size 1.27 1.27)
				)
				(justify mirror)
			)
		)
		(duplicate_pad_numbers_are_jumpers no)
		(fp_line
			(start 0.7874 -0.4064)
			(end -0.7874 -0.4064)
			(stroke
				(width 0.1524)
				(type default)
			)
			(layer "B.SilkS")
		)
		(fp_line
			(start -0.7874 -0.4064)
			(end -0.7874 0.4064)
			(stroke
				(width 0.1524)
				(type default)
			)
			(layer "B.SilkS")
		)
		(fp_line
			(start 0.7874 0.4064)
			(end 0.7874 -0.4064)
			(stroke
				(width 0.1524)
				(type default)
			)
			(layer "B.SilkS")
		)
		(fp_line
			(start -0.7874 0.4064)
			(end 0.7874 0.4064)
			(stroke
				(width 0.1524)
				(type default)
			)
			(layer "B.SilkS")
		)
		(fp_line
			(start 0.67945 -0.305054)
			(end 0.12065 -0.305054)
			(stroke
				(width 0.1)
				(type default)
			)
			(layer "B.Fab")
		)
		(fp_line
			(start 0.12065 -0.305054)
			(end 0.12065 -0.2794)
			(stroke
				(width 0.1)
				(type default)
			)
			(layer "B.Fab")
		)
		(fp_line
			(start -0.12065 -0.3048)
			(end -0.67945 -0.3048)
			(stroke
				(width 0.1)
				(type default)
			)
			(layer "B.Fab")
		)
		(fp_line
			(start -0.67945 -0.3048)
			(end -0.67945 0.3048)
			(stroke
				(width 0.1)
				(type default)
			)
			(layer "B.Fab")
		)
		(fp_line
			(start 0.12065 -0.2794)
			(end -0.12065 -0.2794)
			(stroke
				(width 0.1)
				(type default)
			)
			(layer "B.Fab")
		)
		(fp_line
			(start -0.12065 -0.2794)
			(end -0.12065 -0.3048)
			(stroke
				(width 0.1)
				(type default)
			)
			(layer "B.Fab")
		)
		(fp_line
			(start 0.12065 0.2794)
			(end 0.12065 0.3048)
			(stroke
				(width 0.1)
				(type default)
			)
			(layer "B.Fab")
		)
		(fp_line
			(start -0.120396 0.2794)
			(end 0.12065 0.2794)
			(stroke
				(width 0.1)
				(type default)
			)
			(layer "B.Fab")
		)
		(fp_line
			(start 0.67945 0.3048)
			(end 0.67945 -0.305054)
			(stroke
				(width 0.1)
				(type default)
			)
			(layer "B.Fab")
		)
		(fp_line
			(start 0.12065 0.3048)
			(end 0.67945 0.3048)
			(stroke
				(width 0.1)
				(type default)
			)
			(layer "B.Fab")
		)
		(fp_line
			(start -0.120396 0.3048)
			(end -0.120396 0.2794)
			(stroke
				(width 0.1)
				(type default)
			)
			(layer "B.Fab")
		)
		(fp_line
			(start -0.67945 0.3048)
			(end -0.120396 0.3048)
			(stroke
				(width 0.1)
				(type default)
			)
			(layer "B.Fab")
		)
		(pad "1" smd circle
			(at 0.40005 0 270)
			(size 0 0)
			(layers "B.Cu" "B.Mask" "B.Paste")
			(net "HGX_DETECT_N_ISO")
		)
		(pad "2" smd circle
			(at -0.40005 0 270)
			(size 0 0)
			(layers "B.Cu" "B.Mask" "B.Paste")
			(net "GND")
		)
	)
	(footprint ""
		(layer "B.Cu")
		(at 193.171318 -140.432536 90)
		(property "Reference" "R633"
			(at 0 0 90)
			(layer "B.SilkS")
			(hide yes)
			(effects
				(font
					(size 1.27 1.27)
				)
				(justify mirror)
			)
		)
		(property "Value" ""
			(at 0 0 90)
			(layer "B.Fab")
			(effects
				(font
					(size 1.27 1.27)
				)
				(justify mirror)
			)
		)
		(duplicate_pad_numbers_are_jumpers no)
		(fp_line
			(start 0.7874 -0.4064)
			(end -0.7874 -0.4064)
			(stroke
				(width 0.1524)
				(type default)
			)
			(layer "B.SilkS")
		)
		(fp_line
			(start -0.7874 -0.4064)
			(end -0.7874 0.4064)
			(stroke
				(width 0.1524)
				(type default)
			)
			(layer "B.SilkS")
		)
		(fp_line
			(start 0.7874 0.4064)
			(end 0.7874 -0.4064)
			(stroke
				(width 0.1524)
				(type default)
			)
			(layer "B.SilkS")
		)
		(fp_line
			(start -0.7874 0.4064)
			(end 0.7874 0.4064)
			(stroke
				(width 0.1524)
				(type default)
			)
			(layer "B.SilkS")
		)
		(fp_line
			(start 0.67945 -0.305054)
			(end 0.12065 -0.305054)
			(stroke
				(width 0.1)
				(type default)
			)
			(layer "B.Fab")
		)
		(fp_line
			(start 0.12065 -0.305054)
			(end 0.12065 -0.2794)
			(stroke
				(width 0.1)
				(type default)
			)
			(layer "B.Fab")
		)
		(fp_line
			(start -0.12065 -0.3048)
			(end -0.67945 -0.3048)
			(stroke
				(width 0.1)
				(type default)
			)
			(layer "B.Fab")
		)
		(fp_line
			(start -0.67945 -0.3048)
			(end -0.67945 0.3048)
			(stroke
				(width 0.1)
				(type default)
			)
			(layer "B.Fab")
		)
		(fp_line
			(start 0.12065 -0.2794)
			(end -0.12065 -0.2794)
			(stroke
				(width 0.1)
				(type default)
			)
			(layer "B.Fab")
		)
		(fp_line
			(start -0.12065 -0.2794)
			(end -0.12065 -0.3048)
			(stroke
				(width 0.1)
				(type default)
			)
			(layer "B.Fab")
		)
		(fp_line
			(start 0.12065 0.2794)
			(end 0.12065 0.3048)
			(stroke
				(width 0.1)
				(type default)
			)
			(layer "B.Fab")
		)
		(fp_line
			(start -0.120396 0.2794)
			(end 0.12065 0.2794)
			(stroke
				(width 0.1)
				(type default)
			)
			(layer "B.Fab")
		)
		(fp_line
			(start 0.67945 0.3048)
			(end 0.67945 -0.305054)
			(stroke
				(width 0.1)
				(type default)
			)
			(layer "B.Fab")
		)
		(fp_line
			(start 0.12065 0.3048)
			(end 0.67945 0.3048)
			(stroke
				(width 0.1)
				(type default)
			)
			(layer "B.Fab")
		)
		(fp_line
			(start -0.120396 0.3048)
			(end -0.120396 0.2794)
			(stroke
				(width 0.1)
				(type default)
			)
			(layer "B.Fab")
		)
		(fp_line
			(start -0.67945 0.3048)
			(end -0.120396 0.3048)
			(stroke
				(width 0.1)
				(type default)
			)
			(layer "B.Fab")
		)
		(pad "1" smd circle
			(at 0.40005 0 270)
			(size 0 0)
			(layers "B.Cu" "B.Mask" "B.Paste")
			(net "PVDD18_S5_P0")
		)
		(pad "2" smd circle
			(at -0.40005 0 270)
			(size 0 0)
			(layers "B.Cu" "B.Mask" "B.Paste")
			(net "SMB_CPU_5_SDA")
		)
	)
	(footprint ""
		(layer "B.Cu")
		(at 43.247564 -337.989672 -90)
		(property "Reference" "PC458_2"
			(at 0 0 90)
			(layer "B.SilkS")
			(hide yes)
			(effects
				(font
					(size 1.27 1.27)
				)
				(justify mirror)
			)
		)
		(property "Value" ""
			(at 0 0 90)
			(layer "B.Fab")
			(effects
				(font
					(size 1.27 1.27)
				)
				(justify mirror)
			)
		)
		(duplicate_pad_numbers_are_jumpers no)
		(fp_line
			(start -1.524 0.762)
			(end 1.524 0.762)
			(stroke
				(width 0.1524)
				(type default)
			)
			(layer "B.SilkS")
		)
		(fp_line
			(start 1.524 0.762)
			(end 1.524 -0.762)
			(stroke
				(width 0.1524)
				(type default)
			)
			(layer "B.SilkS")
		)
		(fp_line
			(start -1.524 -0.762)
			(end -1.524 0.762)
			(stroke
				(width 0.1524)
				(type default)
			)
			(layer "B.SilkS")
		)
		(fp_line
			(start 1.524 -0.762)
			(end -1.524 -0.762)
			(stroke
				(width 0.1524)
				(type default)
			)
			(layer "B.SilkS")
		)
		(fp_line
			(start -1.1049 0.724916)
			(end -1.1049 -0.724916)
			(stroke
				(width 0.1)
				(type default)
			)
			(layer "B.Fab")
		)
		(fp_line
			(start 1.1049 0.724916)
			(end -1.1049 0.724916)
			(stroke
				(width 0.1)
				(type default)
			)
			(layer "B.Fab")
		)
		(fp_line
			(start -1.1049 -0.724916)
			(end 1.1049 -0.724916)
			(stroke
				(width 0.1)
				(type default)
			)
			(layer "B.Fab")
		)
		(fp_line
			(start 1.1049 -0.724916)
			(end 1.1049 0.724916)
			(stroke
				(width 0.1)
				(type default)
			)
			(layer "B.Fab")
		)
		(pad "1" smd rect
			(at 0.889 0 270)
			(size 1.016 1.27)
			(layers "B.Cu" "B.Mask" "B.Paste")
			(net "PVDDIO_P1")
		)
		(pad "2" smd rect
			(at -0.889 0 270)
			(size 1.016 1.27)
			(layers "B.Cu" "B.Mask" "B.Paste")
			(net "GND")
		)
	)
)
